(kicad_pcb
	(version 20260206)
	(generator "pcbnew")
	(generator_version "10.0")
	(general
		(thickness 1.6)
		(legacy_teardrops no)
	)
	(paper "A4")
	(title_block
		(title "Wiwynn_Tioga_Pass_MB.brd")
		(comment 1 "Tioga Pass / footprints 2126-2128 of 4770")
	)
	(layers
		(0 "F.Cu" signal "TOP")
		(4 "In1.Cu" signal "L2GND")
		(6 "In2.Cu" signal "L3")
		(8 "In3.Cu" signal "L4GND")
		(10 "In4.Cu" signal "L5")
		(12 "In5.Cu" signal "L6GND")
		(14 "In6.Cu" signal "L7VCC")
		(16 "In7.Cu" signal "L8VCC")
		(18 "In8.Cu" signal "L9GND")
		(20 "In9.Cu" signal "L10")
		(22 "In10.Cu" signal "L11GND")
		(24 "In11.Cu" signal "L12")
		(26 "In12.Cu" signal "L13GND")
		(2 "B.Cu" signal "BOTTOM")
		(9 "F.Adhes" user "F.Adhesive")
		(11 "B.Adhes" user "B.Adhesive")
		(13 "F.Paste" user "Package Geometry/Pastemask Top")
		(15 "B.Paste" user "Package Geometry/Pastemask Bottom")
		(5 "F.SilkS" user "Ref Des/Silkscreen Top")
		(7 "B.SilkS" user "Ref Des/Silkscreen Bottom")
		(1 "F.Mask" user "Board Geometry/Soldermask Top")
		(3 "B.Mask" user "Board Geometry/Soldermask Bottom")
		(17 "Dwgs.User" user "User.Drawings")
		(19 "Cmts.User" user "User.Comments")
		(21 "Eco1.User" user "User.Eco1")
		(23 "Eco2.User" user "User.Eco2")
		(25 "Edge.Cuts" user "Board Geometry/Outline")
		(27 "Margin" user)
		(31 "F.CrtYd" user "Package Geometry/Place Bound Top")
		(29 "B.CrtYd" user "Package Geometry/Place Bound Bottom")
		(35 "F.Fab" user "Ref Des/Assembly Top")
		(33 "B.Fab" user "Ref Des/Assembly Bottom")
	)
	(footprint ""
		(layer "F.Cu")
		(at 437.930036 -135.64489 180)
		(property "Reference" "J2W2"
			(at 0 0 180)
			(layer "F.SilkS")
			(hide yes)
			(effects
				(font
					(size 1.27 1.27)
				)
			)
		)
		(property "Value" "*"
			(at -2.3622 -8.3185 180)
			(unlocked yes)
			(layer "F.Fab")
			(hide yes)
			(effects
				(font
					(size 1.27 1.016)
					(thickness 0.1524)
				)
			)
		)
		(property "Device Type" "SKT-SATA7P-6P-165-GP-U1_SOCKETA"
			(at -2.3622 -9.8425 180)
			(unlocked yes)
			(layer "F.Fab")
			(hide yes)
			(effects
				(font
					(size 1.27 1.016)
					(thickness 0.1524)
				)
			)
		)
		(duplicate_pad_numbers_are_jumpers no)
		(fp_line
			(start 17.8054 2.9337)
			(end -17.8054 2.9337)
			(stroke
				(width 0.1524)
				(type default)
			)
			(layer "F.SilkS")
		)
		(fp_line
			(start 17.8054 -3.3909)
			(end 17.8054 2.9337)
			(stroke
				(width 0.1524)
				(type default)
			)
			(layer "F.SilkS")
		)
		(fp_line
			(start -3.68808 0.649224)
			(end -3.68808 0.750824)
			(stroke
				(width 0.3048)
				(type default)
			)
			(layer "F.SilkS")
		)
		(fp_line
			(start -10.21207 0.750824)
			(end -10.21207 0.649224)
			(stroke
				(width 0.3048)
				(type default)
			)
			(layer "F.SilkS")
		)
		(fp_line
			(start -17.8054 2.9337)
			(end -17.8054 -3.3909)
			(stroke
				(width 0.1524)
				(type default)
			)
			(layer "F.SilkS")
		)
		(fp_line
			(start -17.8054 -3.3909)
			(end 17.8054 -3.3909)
			(stroke
				(width 0.1524)
				(type default)
			)
			(layer "F.SilkS")
		)
		(fp_arc
			(start 8.744966 1.28524)
			(mid 8.109966 1.563565)
			(end 7.474966 1.28524)
			(stroke
				(width 0.3048)
				(type default)
			)
			(layer "F.SilkS")
		)
		(fp_arc
			(start 8.744966 0.114808)
			(mid 10.243507 0.700024)
			(end 8.744966 1.28524)
			(stroke
				(width 0.3048)
				(type default)
			)
			(layer "F.SilkS")
		)
		(fp_arc
			(start 7.474966 1.28524)
			(mid 6.839966 1.563565)
			(end 6.204966 1.28524)
			(stroke
				(width 0.3048)
				(type default)
			)
			(layer "F.SilkS")
		)
		(fp_arc
			(start 7.474966 0.114808)
			(mid 8.109966 -0.163517)
			(end 8.744966 0.114808)
			(stroke
				(width 0.3048)
				(type default)
			)
			(layer "F.SilkS")
		)
		(fp_arc
			(start 6.204966 1.28524)
			(mid 5.569966 1.563565)
			(end 4.934966 1.28524)
			(stroke
				(width 0.3048)
				(type default)
			)
			(layer "F.SilkS")
		)
		(fp_arc
			(start 6.204966 0.114808)
			(mid 6.839966 -0.163517)
			(end 7.474966 0.114808)
			(stroke
				(width 0.3048)
				(type default)
			)
			(layer "F.SilkS")
		)
		(fp_arc
			(start 4.934966 1.28524)
			(mid 4.299966 1.563565)
			(end 3.664966 1.28524)
			(stroke
				(width 0.3048)
				(type default)
			)
			(layer "F.SilkS")
		)
		(fp_arc
			(start 4.934966 0.114808)
			(mid 5.569966 -0.163517)
			(end 6.204966 0.114808)
			(stroke
				(width 0.3048)
				(type default)
			)
			(layer "F.SilkS")
		)
		(fp_arc
			(start 3.664966 1.28524)
			(mid 3.029966 1.563565)
			(end 2.394966 1.28524)
			(stroke
				(width 0.3048)
				(type default)
			)
			(layer "F.SilkS")
		)
		(fp_arc
			(start 3.664966 0.114808)
			(mid 4.299966 -0.163517)
			(end 4.934966 0.114808)
			(stroke
				(width 0.3048)
				(type default)
			)
			(layer "F.SilkS")
		)
		(fp_arc
			(start 2.394966 1.28524)
			(mid 0.896425 0.700024)
			(end 2.394966 0.114808)
			(stroke
				(width 0.3048)
				(type default)
			)
			(layer "F.SilkS")
		)
		(fp_arc
			(start 2.394966 0.114808)
			(mid 3.029966 -0.163517)
			(end 3.664966 0.114808)
			(stroke
				(width 0.3048)
				(type default)
			)
			(layer "F.SilkS")
		)
		(fp_arc
			(start -3.68808 0.750824)
			(mid -4.134078 1.444212)
			(end -4.949952 1.32588)
			(stroke
				(width 0.3048)
				(type default)
			)
			(layer "F.SilkS")
		)
		(fp_arc
			(start -4.949952 1.32588)
			(mid -5.450078 1.512936)
			(end -5.950204 1.32588)
			(stroke
				(width 0.3048)
				(type default)
			)
			(layer "F.SilkS")
		)
		(fp_arc
			(start -4.949952 0.074168)
			(mid -4.134101 -0.044115)
			(end -3.68808 0.649224)
			(stroke
				(width 0.3048)
				(type default)
			)
			(layer "F.SilkS")
		)
		(fp_arc
			(start -5.950204 1.32588)
			(mid -6.450076 1.51277)
			(end -6.949948 1.32588)
			(stroke
				(width 0.3048)
				(type default)
			)
			(layer "F.SilkS")
		)
		(fp_arc
			(start -5.950204 0.074168)
			(mid -5.450078 -0.112888)
			(end -4.949952 0.074168)
			(stroke
				(width 0.3048)
				(type default)
			)
			(layer "F.SilkS")
		)
		(fp_arc
			(start -6.949948 1.32588)
			(mid -7.450074 1.512936)
			(end -7.9502 1.32588)
			(stroke
				(width 0.3048)
				(type default)
			)
			(layer "F.SilkS")
		)
		(fp_arc
			(start -6.949948 0.074168)
			(mid -6.450076 -0.112722)
			(end -5.950204 0.074168)
			(stroke
				(width 0.3048)
				(type default)
			)
			(layer "F.SilkS")
		)
		(fp_arc
			(start -7.9502 1.32588)
			(mid -8.450072 1.51277)
			(end -8.949944 1.32588)
			(stroke
				(width 0.3048)
				(type default)
			)
			(layer "F.SilkS")
		)
		(fp_arc
			(start -7.9502 0.074168)
			(mid -7.450074 -0.112888)
			(end -6.949948 0.074168)
			(stroke
				(width 0.3048)
				(type default)
			)
			(layer "F.SilkS")
		)
		(fp_arc
			(start -8.949944 1.32588)
			(mid -9.766031 1.444354)
			(end -10.21207 0.750824)
			(stroke
				(width 0.3048)
				(type default)
			)
			(layer "F.SilkS")
		)
		(fp_arc
			(start -8.949944 0.074168)
			(mid -8.450072 -0.112722)
			(end -7.9502 0.074168)
			(stroke
				(width 0.3048)
				(type default)
			)
			(layer "F.SilkS")
		)
		(fp_arc
			(start -10.21207 0.649224)
			(mid -9.765985 -0.044204)
			(end -8.949944 0.074168)
			(stroke
				(width 0.3048)
				(type default)
			)
			(layer "F.SilkS")
		)
		(fp_poly
			(pts
				(xy -15.9512 -3.1369) (xy -15.9512 -1.2446) (xy -17.0053 -1.2446) (xy -17.0053 1.2446) (xy -15.9512 1.2446)
				(xy -15.9512 2.6797) (xy 15.9512 2.6797) (xy 15.9512 1.2446) (xy 17.0053 1.2446) (xy 17.0053 -1.2446)
				(xy 15.9512 -1.2446) (xy 15.9512 -3.1369)
			)
			(stroke
				(width 0)
				(type default)
			)
			(fill no)
			(layer "F.CrtYd")
		)
		(fp_poly
			(pts
				(xy -18.0594 3.1877) (xy -18.0594 -3.6449) (xy 18.0594 -3.6449) (xy 18.0594 3.1877) (xy -0.4953 3.1877)
				(xy -0.4953 2.6797) (xy 15.9512 2.6797) (xy 15.9512 1.2446) (xy 17.0053 1.2446) (xy 17.0053 -1.2446)
				(xy 15.9512 -1.2446) (xy 15.9512 -3.1369) (xy -15.9512 -3.1369) (xy -15.9512 -1.2446) (xy -17.0053 -1.2446)
				(xy -17.0053 1.2446) (xy -15.9512 1.2446) (xy -15.9512 2.6797) (xy -0.508 2.6797) (xy -0.508 3.1877)
			)
			(stroke
				(width 0)
				(type default)
			)
			(fill no)
			(layer "F.CrtYd")
		)
		(fp_rect
			(start -18.0594 3.1877)
			(end 18.0594 -3.6449)
			(stroke
				(width 0)
				(type default)
			)
			(fill no)
			(layer "F.Fab")
		)
		(pad "" np_thru_hole circle
			(at -12.500102 -1.400048 180)
			(size 0.254 0.254)
			(drill 1.651)
			(layers "*.Cu" "*.Mask")
			(clearance 1.0541)
			(thermal_gap 1.0541)
		)
		(pad "" np_thru_hole circle
			(at 12.500102 -1.400048 180)
			(size 0.254 0.254)
			(drill 1.651)
			(layers "*.Cu" "*.Mask")
			(clearance 1.0541)
			(thermal_gap 1.0541)
		)
		(pad "H1" smd rect
			(at 16.249904 0 180)
			(size 2.5908 3.683)
			(layers "F.Cu" "F.Mask" "F.Paste")
			(net "GND")
		)
		(pad "H2" smd rect
			(at -16.249904 0 180)
			(size 2.5908 3.683)
			(layers "F.Cu" "F.Mask" "F.Paste")
			(net "GND")
		)
		(pad "P1" thru_hole oval
			(at -4.45008 0.700024 180)
			(size 0.8128 0.9144)
			(drill 0.5588)
			(layers "*.Cu" "*.Mask")
			(remove_unused_layers no)
			(net "P5V_HDD_SATA")
			(clearance 0.2286)
			(thermal_gap 0.2286)
		)
		(pad "P2" thru_hole oval
			(at -5.450078 0.700024 180)
			(size 0.8128 0.9144)
			(drill 0.5588)
			(layers "*.Cu" "*.Mask")
			(remove_unused_layers no)
			(net "P5V_HDD_SATA")
			(clearance 0.2286)
			(thermal_gap 0.2286)
		)
		(pad "P3" thru_hole oval
			(at -6.450076 0.700024 180)
			(size 0.8128 0.9144)
			(drill 0.5588)
			(layers "*.Cu" "*.Mask")
			(remove_unused_layers no)
			(net "GND")
			(clearance 0.2286)
			(thermal_gap 0.2286)
		)
		(pad "P4" thru_hole oval
			(at -7.450074 0.700024 180)
			(size 0.8128 0.9144)
			(drill 0.5588)
			(layers "*.Cu" "*.Mask")
			(remove_unused_layers no)
			(net "GND")
			(clearance 0.2286)
			(thermal_gap 0.2286)
		)
		(pad "P5" thru_hole oval
			(at -8.450072 0.700024 180)
			(size 0.8128 0.9144)
			(drill 0.5588)
			(layers "*.Cu" "*.Mask")
			(remove_unused_layers no)
			(net "P12V_HDD_SATA")
			(clearance 0.2286)
			(thermal_gap 0.2286)
		)
		(pad "P6" thru_hole oval
			(at -9.45007 0.700024 180)
			(size 0.8128 0.9144)
			(drill 0.5588)
			(layers "*.Cu" "*.Mask")
			(remove_unused_layers no)
			(net "P12V_HDD_SATA")
			(clearance 0.2286)
			(thermal_gap 0.2286)
		)
		(pad "S1" thru_hole circle
			(at 9.379966 0.700024 180)
			(size 1.016 1.016)
			(drill 0.6604)
			(layers "*.Cu" "*.Mask")
			(remove_unused_layers no)
			(net "GND")
			(clearance 0.1778)
			(thermal_gap 0.1778)
		)
		(pad "S2" thru_hole circle
			(at 8.109966 0.700024 180)
			(size 1.016 1.016)
			(drill 0.6604)
			(layers "*.Cu" "*.Mask")
			(remove_unused_layers no)
			(net "SATA6G_S1_TX_C_DP")
			(clearance 0.1778)
			(thermal_gap 0.1778)
		)
		(pad "S3" thru_hole circle
			(at 6.839966 0.700024 180)
			(size 1.016 1.016)
			(drill 0.6604)
			(layers "*.Cu" "*.Mask")
			(remove_unused_layers no)
			(net "SATA6G_S1_TX_C_DN")
			(clearance 0.1778)
			(thermal_gap 0.1778)
		)
		(pad "S4" thru_hole circle
			(at 5.569966 0.700024 180)
			(size 1.016 1.016)
			(drill 0.6604)
			(layers "*.Cu" "*.Mask")
			(remove_unused_layers no)
			(net "GND")
			(clearance 0.1778)
			(thermal_gap 0.1778)
		)
		(pad "S5" thru_hole circle
			(at 4.299966 0.700024 180)
			(size 1.016 1.016)
			(drill 0.6604)
			(layers "*.Cu" "*.Mask")
			(remove_unused_layers no)
			(net "SATA6G_S1_RX_C_DN")
			(clearance 0.1778)
			(thermal_gap 0.1778)
		)
		(pad "S6" thru_hole circle
			(at 3.029966 0.700024 180)
			(size 1.016 1.016)
			(drill 0.6604)
			(layers "*.Cu" "*.Mask")
			(remove_unused_layers no)
			(net "SATA6G_S1_RX_C_DP")
			(clearance 0.1778)
			(thermal_gap 0.1778)
		)
		(pad "S7" thru_hole circle
			(at 1.759966 0.700024 180)
			(size 1.016 1.016)
			(drill 0.6604)
			(layers "*.Cu" "*.Mask")
			(remove_unused_layers no)
			(net "GND")
			(clearance 0.1778)
			(thermal_gap 0.1778)
		)
		(zone
			(layers "F.Cu" "B.Cu" "In1.Cu" "In2.Cu" "In3.Cu" "In4.Cu" "In5.Cu" "In6.Cu"
				"In7.Cu" "In8.Cu" "In9.Cu" "In10.Cu" "In11.Cu" "In12.Cu"
			)
			(hatch none 0.5)
			(connect_pads
				(clearance 0)
			)
			(min_thickness 0.25)
			(keepout
				(tracks not_allowed)
				(vias allowed)
				(pads allowed)
				(copperpour not_allowed)
				(footprints allowed)
			)
			(placement
				(enabled no)
				(sheetname "")
			)
			(fill
				(thermal_gap 0.5)
				(thermal_bridge_width 0.5)
				(island_removal_mode 0)
			)
			(polygon
				(pts
					(arc
						(start 426.560234 -134.244842)
						(mid 424.299634 -134.244842)
						(end 426.560234 -134.244842)
					)
				)
			)
		)
		(zone
			(layers "F.Cu" "B.Cu" "In1.Cu" "In2.Cu" "In3.Cu" "In4.Cu" "In5.Cu" "In6.Cu"
				"In7.Cu" "In8.Cu" "In9.Cu" "In10.Cu" "In11.Cu" "In12.Cu"
			)
			(hatch none 0.5)
			(connect_pads
				(clearance 0)
			)
			(min_thickness 0.25)
			(keepout
				(tracks not_allowed)
				(vias allowed)
				(pads allowed)
				(copperpour not_allowed)
				(footprints allowed)
			)
			(placement
				(enabled no)
				(sheetname "")
			)
			(fill
				(thermal_gap 0.5)
				(thermal_bridge_width 0.5)
				(island_removal_mode 0)
			)
			(polygon
				(pts
					(arc
						(start 451.560438 -134.244842)
						(mid 449.299838 -134.244842)
						(end 451.560438 -134.244842)
					)
				)
			)
		)
	)
	(footprint ""
		(layer "F.Cu")
		(at 32.352234 -93.625162 -90)
		(property "Reference" "C1C5"
			(at 0 0 270)
			(layer "F.SilkS")
			(hide yes)
			(effects
				(font
					(size 1.27 1.27)
				)
			)
		)
		(property "Value" ""
			(at 0 0 270)
			(layer "F.Fab")
			(effects
				(font
					(size 1.27 1.27)
				)
			)
		)
		(duplicate_pad_numbers_are_jumpers no)
		(fp_rect
			(start 0.3048 0.9906)
			(end -0.3048 -0.1016)
			(stroke
				(width 0)
				(type default)
			)
			(fill no)
			(layer "F.CrtYd")
		)
		(fp_line
			(start -0.3048 0.9906)
			(end 0.3048 0.9906)
			(stroke
				(width 0.1)
				(type default)
			)
			(layer "F.Fab")
		)
		(fp_line
			(start 0.3048 0.9906)
			(end 0.3048 -0.1016)
			(stroke
				(width 0.1)
				(type default)
			)
			(layer "F.Fab")
		)
		(fp_line
			(start -0.3048 -0.1016)
			(end -0.3048 0.9906)
			(stroke
				(width 0.1)
				(type default)
			)
			(layer "F.Fab")
		)
		(fp_line
			(start 0.3048 -0.1016)
			(end -0.3048 -0.1016)
			(stroke
				(width 0.1)
				(type default)
			)
			(layer "F.Fab")
		)
		(pad "1" smd rect
			(at 0 0 270)
			(size 0.508 0.508)
			(layers "F.Cu" "F.Mask" "F.Paste")
			(net "VR_PVSA_CPU1_VCIN")
		)
		(pad "2" smd rect
			(at 0 0.889 270)
			(size 0.508 0.508)
			(layers "F.Cu" "F.Mask" "F.Paste")
			(net "GND")
		)
		(zone
			(layer "F.Cu")
			(hatch none 0.5)
			(connect_pads
				(clearance 0)
			)
			(min_thickness 0.25)
			(keepout
				(tracks allowed)
				(vias not_allowed)
				(pads allowed)
				(copperpour not_allowed)
				(footprints allowed)
			)
			(placement
				(enabled no)
				(sheetname "")
			)
			(fill
				(thermal_gap 0.5)
				(thermal_bridge_width 0.5)
				(island_removal_mode 0)
			)
			(polygon
				(pts
					(xy 31.717234 -93.371162) (xy 32.098234 -93.371162) (xy 32.098234 -93.879162) (xy 31.717234 -93.879162)
				)
			)
		)
		(zone
			(layer "F.Cu")
			(hatch none 0.5)
			(connect_pads
				(clearance 0)
			)
			(min_thickness 0.25)
			(keepout
				(tracks not_allowed)
				(vias allowed)
				(pads allowed)
				(copperpour not_allowed)
				(footprints allowed)
			)
			(placement
				(enabled no)
				(sheetname "")
			)
			(fill
				(thermal_gap 0.5)
				(thermal_bridge_width 0.5)
				(island_removal_mode 0)
			)
			(polygon
				(pts
					(xy 31.717234 -93.371162) (xy 32.098234 -93.371162) (xy 32.098234 -93.879162) (xy 31.717234 -93.879162)
				)
			)
		)
	)
	(footprint ""
		(layer "F.Cu")
		(at 381.2159 -137.4648)
		(property "Reference" "C7A31"
			(at 0 0 0)
			(layer "F.SilkS")
			(hide yes)
			(effects
				(font
					(size 1.27 1.27)
				)
			)
		)
		(property "Value" ""
			(at 0 0 0)
			(layer "F.Fab")
			(effects
				(font
					(size 1.27 1.27)
				)
			)
		)
		(duplicate_pad_numbers_are_jumpers no)
		(fp_rect
			(start -0.7239 1.9939)
			(end 0.7239 -0.2159)
			(stroke
				(width 0)
				(type default)
			)
			(fill no)
			(layer "F.CrtYd")
		)
		(fp_line
			(start -0.7239 -0.2159)
			(end -0.7239 1.9939)
			(stroke
				(width 0.1)
				(type default)
			)
			(layer "F.Fab")
		)
		(fp_line
			(start -0.7239 1.9939)
			(end 0.7239 1.9939)
			(stroke
				(width 0.1)
				(type default)
			)
			(layer "F.Fab")
		)
		(fp_line
			(start 0.7239 -0.2159)
			(end -0.7239 -0.2159)
			(stroke
				(width 0.1)
				(type default)
			)
			(layer "F.Fab")
		)
		(fp_line
			(start 0.7239 1.9939)
			(end 0.7239 -0.2159)
			(stroke
				(width 0.1)
				(type default)
			)
			(layer "F.Fab")
		)
		(pad "1" smd rect
			(at 0 0)
			(size 1.27 1.016)
			(layers "F.Cu" "F.Mask" "F.Paste")
			(net "PVNN_PCH_STBY")
		)
		(pad "2" smd rect
			(at 0 1.778)
			(size 1.27 1.016)
			(layers "F.Cu" "F.Mask" "F.Paste")
			(net "GND")
		)
		(zone
			(layer "F.Cu")
			(hatch none 0.5)
			(connect_pads
				(clearance 0)
			)
			(min_thickness 0.25)
			(keepout
				(tracks not_allowed)
				(vias allowed)
				(pads allowed)
				(copperpour not_allowed)
				(footprints allowed)
			)
			(placement
				(enabled no)
				(sheetname "")
			)
			(fill
				(thermal_gap 0.5)
				(thermal_bridge_width 0.5)
				(island_removal_mode 0)
			)
			(polygon
				(pts
					(xy 380.5809 -136.1948) (xy 381.8509 -136.1948) (xy 381.8509 -136.9568) (xy 380.5809 -136.9568)
				)
			)
		)
	)
)
